(kicad_pcb
	(version 20260206)
	(generator "pcbnew")
	(generator_version "10.0")
	(general
		(thickness 1.6)
		(legacy_teardrops no)
	)
	(paper "A4")
	(title_block
		(title "03242023_DA0F0TMBIJ0_F0T_Motherboard_J_brd_V01_OCP.brd")
		(comment 1 "Grand Teton / footprints 4501-4506 of 6105")
	)
	(layers
		(0 "F.Cu" signal "TOP")
		(4 "In1.Cu" signal "GND")
		(6 "In2.Cu" signal "IN1")
		(8 "In3.Cu" signal "GND1")
		(10 "In4.Cu" signal "IN2")
		(12 "In5.Cu" signal "GND2")
		(14 "In6.Cu" signal "IN3")
		(16 "In7.Cu" signal "GND3")
		(18 "In8.Cu" signal "VCC")
		(20 "In9.Cu" signal "VCC1")
		(22 "In10.Cu" signal "GND4")
		(24 "In11.Cu" signal "IN4")
		(26 "In12.Cu" signal "GND5")
		(28 "In13.Cu" signal "IN5")
		(30 "In14.Cu" signal "GND6")
		(32 "In15.Cu" signal "IN6")
		(34 "In16.Cu" signal "GND7")
		(2 "B.Cu" signal "BOTTOM")
		(9 "F.Adhes" user "F.Adhesive")
		(11 "B.Adhes" user "B.Adhesive")
		(13 "F.Paste" user "Package Geometry/Pastemask Top")
		(15 "B.Paste" user "Package Geometry/Pastemask Bottom")
		(5 "F.SilkS" user "Ref Des/Silkscreen Top")
		(7 "B.SilkS" user "Ref Des/Silkscreen Bottom")
		(1 "F.Mask" user "Board Geometry/Soldermask Top")
		(3 "B.Mask" user "Board Geometry/Soldermask Bottom")
		(17 "Dwgs.User" user "User.Drawings")
		(19 "Cmts.User" user "User.Comments")
		(21 "Eco1.User" user "User.Eco1")
		(23 "Eco2.User" user "User.Eco2")
		(25 "Edge.Cuts" user "Board Geometry/Outline")
		(27 "Margin" user)
		(31 "F.CrtYd" user "Package Geometry/Place Bound Top")
		(29 "B.CrtYd" user "Package Geometry/Place Bound Bottom")
		(35 "F.Fab" user "Ref Des/Assembly Top")
		(33 "B.Fab" user "Ref Des/Assembly Bottom")
	)
	(footprint ""
		(layer "B.Cu")
		(at 162.306 -15.712948 -90)
		(property "Reference" "R1384"
			(at 0 0 90)
			(layer "B.SilkS")
			(hide yes)
			(effects
				(font
					(size 1.27 1.27)
				)
				(justify mirror)
			)
		)
		(property "Value" ""
			(at 0 0 90)
			(layer "B.Fab")
			(effects
				(font
					(size 1.27 1.27)
				)
				(justify mirror)
			)
		)
		(duplicate_pad_numbers_are_jumpers no)
		(fp_line
			(start -0.7874 0.4064)
			(end 0.7874 0.4064)
			(stroke
				(width 0.1524)
				(type default)
			)
			(layer "B.SilkS")
		)
		(fp_line
			(start 0.7874 0.4064)
			(end 0.7874 -0.4064)
			(stroke
				(width 0.1524)
				(type default)
			)
			(layer "B.SilkS")
		)
		(fp_line
			(start -0.7874 -0.4064)
			(end -0.7874 0.4064)
			(stroke
				(width 0.1524)
				(type default)
			)
			(layer "B.SilkS")
		)
		(fp_line
			(start 0.7874 -0.4064)
			(end -0.7874 -0.4064)
			(stroke
				(width 0.1524)
				(type default)
			)
			(layer "B.SilkS")
		)
		(fp_line
			(start -0.67945 0.3048)
			(end -0.120396 0.3048)
			(stroke
				(width 0.1)
				(type default)
			)
			(layer "B.Fab")
		)
		(fp_line
			(start -0.120396 0.3048)
			(end -0.120396 0.2794)
			(stroke
				(width 0.1)
				(type default)
			)
			(layer "B.Fab")
		)
		(fp_line
			(start 0.12065 0.3048)
			(end 0.67945 0.3048)
			(stroke
				(width 0.1)
				(type default)
			)
			(layer "B.Fab")
		)
		(fp_line
			(start 0.67945 0.3048)
			(end 0.67945 -0.305054)
			(stroke
				(width 0.1)
				(type default)
			)
			(layer "B.Fab")
		)
		(fp_line
			(start -0.120396 0.2794)
			(end 0.12065 0.2794)
			(stroke
				(width 0.1)
				(type default)
			)
			(layer "B.Fab")
		)
		(fp_line
			(start 0.12065 0.2794)
			(end 0.12065 0.3048)
			(stroke
				(width 0.1)
				(type default)
			)
			(layer "B.Fab")
		)
		(fp_line
			(start -0.12065 -0.2794)
			(end -0.12065 -0.3048)
			(stroke
				(width 0.1)
				(type default)
			)
			(layer "B.Fab")
		)
		(fp_line
			(start 0.12065 -0.2794)
			(end -0.12065 -0.2794)
			(stroke
				(width 0.1)
				(type default)
			)
			(layer "B.Fab")
		)
		(fp_line
			(start -0.67945 -0.3048)
			(end -0.67945 0.3048)
			(stroke
				(width 0.1)
				(type default)
			)
			(layer "B.Fab")
		)
		(fp_line
			(start -0.12065 -0.3048)
			(end -0.67945 -0.3048)
			(stroke
				(width 0.1)
				(type default)
			)
			(layer "B.Fab")
		)
		(fp_line
			(start 0.12065 -0.305054)
			(end 0.12065 -0.2794)
			(stroke
				(width 0.1)
				(type default)
			)
			(layer "B.Fab")
		)
		(fp_line
			(start 0.67945 -0.305054)
			(end 0.12065 -0.305054)
			(stroke
				(width 0.1)
				(type default)
			)
			(layer "B.Fab")
		)
		(pad "1" smd circle
			(at 0.40005 0 90)
			(size 0 0)
			(layers "B.Cu" "B.Mask" "B.Paste")
			(net "SMB_SML0_3V3AUX_SCL")
		)
		(pad "2" smd circle
			(at -0.40005 0 90)
			(size 0 0)
			(layers "B.Cu" "B.Mask" "B.Paste")
			(net "P3V3_AUX")
		)
	)
	(footprint ""
		(layer "B.Cu")
		(at 369.49888 -37.937948 180)
		(property "Reference" "R4117"
			(at 0 0 0)
			(layer "B.SilkS")
			(hide yes)
			(effects
				(font
					(size 1.27 1.27)
				)
				(justify mirror)
			)
		)
		(property "Value" ""
			(at 0 0 0)
			(layer "B.Fab")
			(effects
				(font
					(size 1.27 1.27)
				)
				(justify mirror)
			)
		)
		(duplicate_pad_numbers_are_jumpers no)
		(fp_line
			(start 0.7874 0.4064)
			(end 0.7874 -0.4064)
			(stroke
				(width 0.1524)
				(type default)
			)
			(layer "B.SilkS")
		)
		(fp_line
			(start 0.7874 -0.4064)
			(end -0.7874 -0.4064)
			(stroke
				(width 0.1524)
				(type default)
			)
			(layer "B.SilkS")
		)
		(fp_line
			(start -0.7874 0.4064)
			(end 0.7874 0.4064)
			(stroke
				(width 0.1524)
				(type default)
			)
			(layer "B.SilkS")
		)
		(fp_line
			(start -0.7874 -0.4064)
			(end -0.7874 0.4064)
			(stroke
				(width 0.1524)
				(type default)
			)
			(layer "B.SilkS")
		)
		(fp_line
			(start 0.67945 0.3048)
			(end 0.67945 -0.305054)
			(stroke
				(width 0.1)
				(type default)
			)
			(layer "B.Fab")
		)
		(fp_line
			(start 0.67945 -0.305054)
			(end 0.12065 -0.305054)
			(stroke
				(width 0.1)
				(type default)
			)
			(layer "B.Fab")
		)
		(fp_line
			(start 0.12065 0.3048)
			(end 0.67945 0.3048)
			(stroke
				(width 0.1)
				(type default)
			)
			(layer "B.Fab")
		)
		(fp_line
			(start 0.12065 0.2794)
			(end 0.12065 0.3048)
			(stroke
				(width 0.1)
				(type default)
			)
			(layer "B.Fab")
		)
		(fp_line
			(start 0.12065 -0.2794)
			(end -0.12065 -0.2794)
			(stroke
				(width 0.1)
				(type default)
			)
			(layer "B.Fab")
		)
		(fp_line
			(start 0.12065 -0.305054)
			(end 0.12065 -0.2794)
			(stroke
				(width 0.1)
				(type default)
			)
			(layer "B.Fab")
		)
		(fp_line
			(start -0.120396 0.3048)
			(end -0.120396 0.2794)
			(stroke
				(width 0.1)
				(type default)
			)
			(layer "B.Fab")
		)
		(fp_line
			(start -0.120396 0.2794)
			(end 0.12065 0.2794)
			(stroke
				(width 0.1)
				(type default)
			)
			(layer "B.Fab")
		)
		(fp_line
			(start -0.12065 -0.2794)
			(end -0.12065 -0.3048)
			(stroke
				(width 0.1)
				(type default)
			)
			(layer "B.Fab")
		)
		(fp_line
			(start -0.12065 -0.3048)
			(end -0.67945 -0.3048)
			(stroke
				(width 0.1)
				(type default)
			)
			(layer "B.Fab")
		)
		(fp_line
			(start -0.67945 0.3048)
			(end -0.120396 0.3048)
			(stroke
				(width 0.1)
				(type default)
			)
			(layer "B.Fab")
		)
		(fp_line
			(start -0.67945 -0.3048)
			(end -0.67945 0.3048)
			(stroke
				(width 0.1)
				(type default)
			)
			(layer "B.Fab")
		)
		(pad "1" smd circle
			(at 0.40005 0)
			(size 0 0)
			(layers "B.Cu" "B.Mask" "B.Paste")
			(net "PD_PCH_GPP_E_3")
		)
		(pad "2" smd circle
			(at -0.40005 0)
			(size 0 0)
			(layers "B.Cu" "B.Mask" "B.Paste")
			(net "GND")
		)
	)
	(footprint ""
		(layer "B.Cu")
		(at 36.765992 -178.63058 180)
		(property "Reference" "C1365"
			(at 0 0 0)
			(layer "B.SilkS")
			(hide yes)
			(effects
				(font
					(size 1.27 1.27)
				)
				(justify mirror)
			)
		)
		(property "Value" ""
			(at 0 0 0)
			(layer "B.Fab")
			(effects
				(font
					(size 1.27 1.27)
				)
				(justify mirror)
			)
		)
		(duplicate_pad_numbers_are_jumpers no)
		(fp_line
			(start 0.7874 0.4064)
			(end 0.7874 -0.4064)
			(stroke
				(width 0.1524)
				(type default)
			)
			(layer "B.SilkS")
		)
		(fp_line
			(start 0.7874 -0.4064)
			(end -0.7874 -0.4064)
			(stroke
				(width 0.1524)
				(type default)
			)
			(layer "B.SilkS")
		)
		(fp_line
			(start -0.7874 0.4064)
			(end 0.7874 0.4064)
			(stroke
				(width 0.1524)
				(type default)
			)
			(layer "B.SilkS")
		)
		(fp_line
			(start -0.7874 -0.4064)
			(end -0.7874 0.4064)
			(stroke
				(width 0.1524)
				(type default)
			)
			(layer "B.SilkS")
		)
		(fp_line
			(start 0.67945 0.3048)
			(end 0.67945 -0.305054)
			(stroke
				(width 0.1)
				(type default)
			)
			(layer "B.Fab")
		)
		(fp_line
			(start 0.67945 -0.305054)
			(end 0.12065 -0.305054)
			(stroke
				(width 0.1)
				(type default)
			)
			(layer "B.Fab")
		)
		(fp_line
			(start 0.12065 0.3048)
			(end 0.67945 0.3048)
			(stroke
				(width 0.1)
				(type default)
			)
			(layer "B.Fab")
		)
		(fp_line
			(start 0.12065 0.2794)
			(end 0.12065 0.3048)
			(stroke
				(width 0.1)
				(type default)
			)
			(layer "B.Fab")
		)
		(fp_line
			(start 0.12065 -0.2794)
			(end -0.12065 -0.2794)
			(stroke
				(width 0.1)
				(type default)
			)
			(layer "B.Fab")
		)
		(fp_line
			(start 0.12065 -0.305054)
			(end 0.12065 -0.2794)
			(stroke
				(width 0.1)
				(type default)
			)
			(layer "B.Fab")
		)
		(fp_line
			(start -0.120396 0.3048)
			(end -0.120396 0.2794)
			(stroke
				(width 0.1)
				(type default)
			)
			(layer "B.Fab")
		)
		(fp_line
			(start -0.120396 0.2794)
			(end 0.12065 0.2794)
			(stroke
				(width 0.1)
				(type default)
			)
			(layer "B.Fab")
		)
		(fp_line
			(start -0.12065 -0.2794)
			(end -0.12065 -0.3048)
			(stroke
				(width 0.1)
				(type default)
			)
			(layer "B.Fab")
		)
		(fp_line
			(start -0.12065 -0.3048)
			(end -0.67945 -0.3048)
			(stroke
				(width 0.1)
				(type default)
			)
			(layer "B.Fab")
		)
		(fp_line
			(start -0.67945 0.3048)
			(end -0.120396 0.3048)
			(stroke
				(width 0.1)
				(type default)
			)
			(layer "B.Fab")
		)
		(fp_line
			(start -0.67945 -0.3048)
			(end -0.67945 0.3048)
			(stroke
				(width 0.1)
				(type default)
			)
			(layer "B.Fab")
		)
		(pad "1" smd circle
			(at 0.40005 0)
			(size 0 0)
			(layers "B.Cu" "B.Mask" "B.Paste")
			(net "PVNN_MAIN_CPU1")
		)
		(pad "2" smd circle
			(at -0.40005 0)
			(size 0 0)
			(layers "B.Cu" "B.Mask" "B.Paste")
			(net "GND")
		)
	)
	(footprint ""
		(layer "B.Cu")
		(at 51.14544 -170.495468 90)
		(property "Reference" "PR250"
			(at 0 0 90)
			(layer "B.SilkS")
			(hide yes)
			(effects
				(font
					(size 1.27 1.27)
				)
				(justify mirror)
			)
		)
		(property "Value" ""
			(at 0 0 90)
			(layer "B.Fab")
			(effects
				(font
					(size 1.27 1.27)
				)
				(justify mirror)
			)
		)
		(duplicate_pad_numbers_are_jumpers no)
		(fp_line
			(start 0.7874 -0.4064)
			(end -0.7874 -0.4064)
			(stroke
				(width 0.1524)
				(type default)
			)
			(layer "B.SilkS")
		)
		(fp_line
			(start -0.7874 -0.4064)
			(end -0.7874 0.4064)
			(stroke
				(width 0.1524)
				(type default)
			)
			(layer "B.SilkS")
		)
		(fp_line
			(start 0.7874 0.4064)
			(end 0.7874 -0.4064)
			(stroke
				(width 0.1524)
				(type default)
			)
			(layer "B.SilkS")
		)
		(fp_line
			(start -0.7874 0.4064)
			(end 0.7874 0.4064)
			(stroke
				(width 0.1524)
				(type default)
			)
			(layer "B.SilkS")
		)
		(fp_line
			(start 0.67945 -0.305054)
			(end 0.12065 -0.305054)
			(stroke
				(width 0.1)
				(type default)
			)
			(layer "B.Fab")
		)
		(fp_line
			(start 0.12065 -0.305054)
			(end 0.12065 -0.2794)
			(stroke
				(width 0.1)
				(type default)
			)
			(layer "B.Fab")
		)
		(fp_line
			(start -0.12065 -0.3048)
			(end -0.67945 -0.3048)
			(stroke
				(width 0.1)
				(type default)
			)
			(layer "B.Fab")
		)
		(fp_line
			(start -0.67945 -0.3048)
			(end -0.67945 0.3048)
			(stroke
				(width 0.1)
				(type default)
			)
			(layer "B.Fab")
		)
		(fp_line
			(start 0.12065 -0.2794)
			(end -0.12065 -0.2794)
			(stroke
				(width 0.1)
				(type default)
			)
			(layer "B.Fab")
		)
		(fp_line
			(start -0.12065 -0.2794)
			(end -0.12065 -0.3048)
			(stroke
				(width 0.1)
				(type default)
			)
			(layer "B.Fab")
		)
		(fp_line
			(start 0.12065 0.2794)
			(end 0.12065 0.3048)
			(stroke
				(width 0.1)
				(type default)
			)
			(layer "B.Fab")
		)
		(fp_line
			(start -0.120396 0.2794)
			(end 0.12065 0.2794)
			(stroke
				(width 0.1)
				(type default)
			)
			(layer "B.Fab")
		)
		(fp_line
			(start 0.67945 0.3048)
			(end 0.67945 -0.305054)
			(stroke
				(width 0.1)
				(type default)
			)
			(layer "B.Fab")
		)
		(fp_line
			(start 0.12065 0.3048)
			(end 0.67945 0.3048)
			(stroke
				(width 0.1)
				(type default)
			)
			(layer "B.Fab")
		)
		(fp_line
			(start -0.120396 0.3048)
			(end -0.120396 0.2794)
			(stroke
				(width 0.1)
				(type default)
			)
			(layer "B.Fab")
		)
		(fp_line
			(start -0.67945 0.3048)
			(end -0.120396 0.3048)
			(stroke
				(width 0.1)
				(type default)
			)
			(layer "B.Fab")
		)
		(pad "1" smd circle
			(at 0.40005 0 270)
			(size 0 0)
			(layers "B.Cu" "B.Mask" "B.Paste")
			(net "PVCCFA_EHV_CPU1_PVCC")
		)
		(pad "2" smd circle
			(at -0.40005 0 270)
			(size 0 0)
			(layers "B.Cu" "B.Mask" "B.Paste")
			(net "PVCCFA_EHV_CPU1_VDD1")
		)
	)
	(footprint ""
		(layer "B.Cu")
		(at 308.823614 -258.379976 -90)
		(property "Reference" "C517"
			(at 0 0 90)
			(layer "B.SilkS")
			(hide yes)
			(effects
				(font
					(size 1.27 1.27)
				)
				(justify mirror)
			)
		)
		(property "Value" ""
			(at 0 0 90)
			(layer "B.Fab")
			(effects
				(font
					(size 1.27 1.27)
				)
				(justify mirror)
			)
		)
		(duplicate_pad_numbers_are_jumpers no)
		(fp_line
			(start -1.524 0.762)
			(end 1.524 0.762)
			(stroke
				(width 0.1524)
				(type default)
			)
			(layer "B.SilkS")
		)
		(fp_line
			(start 1.524 0.762)
			(end 1.524 -0.762)
			(stroke
				(width 0.1524)
				(type default)
			)
			(layer "B.SilkS")
		)
		(fp_line
			(start -1.524 -0.762)
			(end -1.524 0.762)
			(stroke
				(width 0.1524)
				(type default)
			)
			(layer "B.SilkS")
		)
		(fp_line
			(start 1.524 -0.762)
			(end -1.524 -0.762)
			(stroke
				(width 0.1524)
				(type default)
			)
			(layer "B.SilkS")
		)
		(fp_line
			(start -1.1049 0.724916)
			(end -1.1049 -0.724916)
			(stroke
				(width 0.1)
				(type default)
			)
			(layer "B.Fab")
		)
		(fp_line
			(start 1.1049 0.724916)
			(end -1.1049 0.724916)
			(stroke
				(width 0.1)
				(type default)
			)
			(layer "B.Fab")
		)
		(fp_line
			(start -1.1049 -0.724916)
			(end 1.1049 -0.724916)
			(stroke
				(width 0.1)
				(type default)
			)
			(layer "B.Fab")
		)
		(fp_line
			(start 1.1049 -0.724916)
			(end 1.1049 0.724916)
			(stroke
				(width 0.1)
				(type default)
			)
			(layer "B.Fab")
		)
		(pad "1" smd rect
			(at 0.889 0 270)
			(size 1.016 1.27)
			(layers "B.Cu" "B.Mask" "B.Paste")
			(net "PVCCFA_EHV_FIVRA_CPU0")
		)
		(pad "2" smd rect
			(at -0.889 0 270)
			(size 1.016 1.27)
			(layers "B.Cu" "B.Mask" "B.Paste")
			(net "GND")
		)
	)
	(footprint ""
		(layer "B.Cu")
		(at 50.698908 -193.25971 -90)
		(property "Reference" "R1393"
			(at 0 0 90)
			(layer "B.SilkS")
			(hide yes)
			(effects
				(font
					(size 1.27 1.27)
				)
				(justify mirror)
			)
		)
		(property "Value" ""
			(at 0 0 90)
			(layer "B.Fab")
			(effects
				(font
					(size 1.27 1.27)
				)
				(justify mirror)
			)
		)
		(duplicate_pad_numbers_are_jumpers no)
		(fp_line
			(start -0.7874 0.4064)
			(end 0.7874 0.4064)
			(stroke
				(width 0.1524)
				(type default)
			)
			(layer "B.SilkS")
		)
		(fp_line
			(start 0.7874 0.4064)
			(end 0.7874 -0.4064)
			(stroke
				(width 0.1524)
				(type default)
			)
			(layer "B.SilkS")
		)
		(fp_line
			(start -0.7874 -0.4064)
			(end -0.7874 0.4064)
			(stroke
				(width 0.1524)
				(type default)
			)
			(layer "B.SilkS")
		)
		(fp_line
			(start 0.7874 -0.4064)
			(end -0.7874 -0.4064)
			(stroke
				(width 0.1524)
				(type default)
			)
			(layer "B.SilkS")
		)
		(fp_line
			(start -0.67945 0.3048)
			(end -0.120396 0.3048)
			(stroke
				(width 0.1)
				(type default)
			)
			(layer "B.Fab")
		)
		(fp_line
			(start -0.120396 0.3048)
			(end -0.120396 0.2794)
			(stroke
				(width 0.1)
				(type default)
			)
			(layer "B.Fab")
		)
		(fp_line
			(start 0.12065 0.3048)
			(end 0.67945 0.3048)
			(stroke
				(width 0.1)
				(type default)
			)
			(layer "B.Fab")
		)
		(fp_line
			(start 0.67945 0.3048)
			(end 0.67945 -0.305054)
			(stroke
				(width 0.1)
				(type default)
			)
			(layer "B.Fab")
		)
		(fp_line
			(start -0.120396 0.2794)
			(end 0.12065 0.2794)
			(stroke
				(width 0.1)
				(type default)
			)
			(layer "B.Fab")
		)
		(fp_line
			(start 0.12065 0.2794)
			(end 0.12065 0.3048)
			(stroke
				(width 0.1)
				(type default)
			)
			(layer "B.Fab")
		)
		(fp_line
			(start -0.12065 -0.2794)
			(end -0.12065 -0.3048)
			(stroke
				(width 0.1)
				(type default)
			)
			(layer "B.Fab")
		)
		(fp_line
			(start 0.12065 -0.2794)
			(end -0.12065 -0.2794)
			(stroke
				(width 0.1)
				(type default)
			)
			(layer "B.Fab")
		)
		(fp_line
			(start -0.67945 -0.3048)
			(end -0.67945 0.3048)
			(stroke
				(width 0.1)
				(type default)
			)
			(layer "B.Fab")
		)
		(fp_line
			(start -0.12065 -0.3048)
			(end -0.67945 -0.3048)
			(stroke
				(width 0.1)
				(type default)
			)
			(layer "B.Fab")
		)
		(fp_line
			(start 0.12065 -0.305054)
			(end 0.12065 -0.2794)
			(stroke
				(width 0.1)
				(type default)
			)
			(layer "B.Fab")
		)
		(fp_line
			(start 0.67945 -0.305054)
			(end 0.12065 -0.305054)
			(stroke
				(width 0.1)
				(type default)
			)
			(layer "B.Fab")
		)
		(pad "1" smd circle
			(at 0.40005 0 90)
			(size 0 0)
			(layers "B.Cu" "B.Mask" "B.Paste")
			(net "GND")
		)
		(pad "2" smd circle
			(at -0.40005 0 90)
			(size 0 0)
			(layers "B.Cu" "B.Mask" "B.Paste")
			(net "FM_S3M_CPU1_LVC1_GPIO_2")
		)
	)
)
